(kicad_pcb
	(version 20260206)
	(generator "pcbnew")
	(generator_version "10.0")
	(general
		(thickness 1.6)
		(legacy_teardrops no)
	)
	(paper "A4")
	(title_block
		(title "Bryce Canyon_SCC_16316-1_OCP.brd")
		(comment 1 "Bryce Canyon / footprints 132-138 of 1561")
	)
	(layers
		(0 "F.Cu" signal "TOP")
		(4 "In1.Cu" signal "L2GND")
		(6 "In2.Cu" signal "L3")
		(8 "In3.Cu" signal "L4VCC")
		(10 "In4.Cu" signal "L5VCC")
		(12 "In5.Cu" signal "L6")
		(14 "In6.Cu" signal "L7GND")
		(2 "B.Cu" signal "BOTTOM")
		(9 "F.Adhes" user "F.Adhesive")
		(11 "B.Adhes" user "B.Adhesive")
		(13 "F.Paste" user "Package Geometry/Pastemask Top")
		(15 "B.Paste" user "Package Geometry/Pastemask Bottom")
		(5 "F.SilkS" user "Ref Des/Silkscreen Top")
		(7 "B.SilkS" user "Ref Des/Silkscreen Bottom")
		(1 "F.Mask" user "Board Geometry/Soldermask Top")
		(3 "B.Mask" user "Board Geometry/Soldermask Bottom")
		(17 "Dwgs.User" user "User.Drawings")
		(19 "Cmts.User" user "User.Comments")
		(21 "Eco1.User" user "User.Eco1")
		(23 "Eco2.User" user "User.Eco2")
		(25 "Edge.Cuts" user "Board Geometry/Outline")
		(27 "Margin" user)
		(31 "F.CrtYd" user "Package Geometry/Place Bound Top")
		(29 "B.CrtYd" user "Package Geometry/Place Bound Bottom")
		(35 "F.Fab" user "Ref Des/Assembly Top")
		(33 "B.Fab" user "Ref Des/Assembly Bottom")
	)
	(footprint ""
		(layer "F.Cu")
		(at 70.866 -101.6)
		(property "Reference" "R518"
			(at 0 0 0)
			(layer "F.SilkS")
			(hide yes)
			(effects
				(font
					(size 1.27 1.27)
				)
			)
		)
		(property "Value" "10KR2F-2-GP"
			(at 0.064008 -3.993896 0)
			(unlocked yes)
			(layer "F.Fab")
			(hide yes)
			(effects
				(font
					(size 1.016 1.016)
					(thickness 0.1524)
				)
			)
		)
		(property "Device Type" "R402H16"
			(at 0.064008 -5.517896 0)
			(unlocked yes)
			(layer "F.Fab")
			(hide yes)
			(effects
				(font
					(size 1.016 1.016)
					(thickness 0.1524)
				)
			)
		)
		(duplicate_pad_numbers_are_jumpers no)
		(fp_line
			(start -0.508 -0.9398)
			(end -0.508 0.9398)
			(stroke
				(width 0.1524)
				(type default)
			)
			(layer "F.SilkS")
		)
		(fp_line
			(start 0.508 -0.9398)
			(end -0.508 -0.9398)
			(stroke
				(width 0.1524)
				(type default)
			)
			(layer "F.SilkS")
		)
		(fp_rect
			(start -0.508 0.9398)
			(end 0.508 -0.9398)
			(stroke
				(width 0)
				(type default)
			)
			(fill no)
			(layer "F.CrtYd")
		)
		(fp_rect
			(start -0.508 0.9398)
			(end 0.508 -0.9398)
			(stroke
				(width 0)
				(type default)
			)
			(fill no)
			(layer "F.Fab")
		)
		(pad "1" smd custom
			(at 0 -0.4445)
			(size 0.1397 0.1397)
			(layers "F.Cu" "F.Mask" "F.Paste")
			(net "P3V3_VFB")
			(options
				(clearance outline)
				(anchor circle)
			)
			(primitives
				(gr_poly
					(pts
						(arc
							(start -0.1778 -0.2794)
							(mid -0.249642 -0.249642)
							(end -0.2794 -0.1778)
						)
						(arc
							(start -0.2794 0.1778)
							(mid -0.249642 0.249642)
							(end -0.1778 0.2794)
						)
						(arc
							(start 0.1778 0.2794)
							(mid 0.249642 0.249642)
							(end 0.2794 0.1778)
						)
						(arc
							(start 0.2794 -0.1778)
							(mid 0.249642 -0.249642)
							(end 0.1778 -0.2794)
						)
					)
					(width 0)
					(fill yes)
				)
			)
		)
		(pad "2" smd custom
			(at 0 0.4445)
			(size 0.1397 0.1397)
			(layers "F.Cu" "F.Mask" "F.Paste")
			(net "AGND_P3V3")
			(options
				(clearance outline)
				(anchor circle)
			)
			(primitives
				(gr_poly
					(pts
						(arc
							(start -0.1778 -0.2794)
							(mid -0.249642 -0.249642)
							(end -0.2794 -0.1778)
						)
						(arc
							(start -0.2794 0.1778)
							(mid -0.249642 0.249642)
							(end -0.1778 0.2794)
						)
						(arc
							(start 0.1778 0.2794)
							(mid 0.249642 0.249642)
							(end 0.2794 0.1778)
						)
						(arc
							(start 0.2794 -0.1778)
							(mid 0.249642 -0.249642)
							(end 0.1778 -0.2794)
						)
					)
					(width 0)
					(fill yes)
				)
			)
		)
	)
	(footprint ""
		(layer "F.Cu")
		(at 61.1632 -71.0438 90)
		(property "Reference" "C552"
			(at 0 0 90)
			(layer "F.SilkS")
			(hide yes)
			(effects
				(font
					(size 1.27 1.27)
				)
			)
		)
		(property "Value" "SCD1U16V2KX-3GP"
			(at 1.1811 -2.7051 90)
			(unlocked yes)
			(layer "F.Fab")
			(hide yes)
			(effects
				(font
					(size 1.016 1.016)
					(thickness 0.1524)
				)
			)
		)
		(property "Device Type" "C402H22"
			(at 1.1811 -4.2291 90)
			(unlocked yes)
			(layer "F.Fab")
			(hide yes)
			(effects
				(font
					(size 1.016 1.016)
					(thickness 0.1524)
				)
			)
		)
		(duplicate_pad_numbers_are_jumpers no)
		(fp_rect
			(start -0.4318 0.9525)
			(end 0.4318 -0.9525)
			(stroke
				(width 0)
				(type default)
			)
			(fill no)
			(layer "F.CrtYd")
		)
		(fp_rect
			(start -0.4318 0.9525)
			(end 0.4318 -0.9525)
			(stroke
				(width 0)
				(type default)
			)
			(fill no)
			(layer "F.Fab")
		)
		(pad "1" smd custom
			(at 0 -0.4445 90)
			(size 0.1524 0.1524)
			(layers "F.Cu" "F.Mask" "F.Paste")
			(net "VREF4")
			(options
				(clearance outline)
				(anchor circle)
			)
			(primitives
				(gr_poly
					(pts
						(arc
							(start 0.3048 -0.2032)
							(mid 0.275042 -0.275042)
							(end 0.2032 -0.3048)
						)
						(arc
							(start -0.2032 -0.3048)
							(mid -0.275042 -0.275042)
							(end -0.3048 -0.2032)
						)
						(arc
							(start -0.3048 0.2032)
							(mid -0.275042 0.275042)
							(end -0.2032 0.3048)
						)
						(arc
							(start 0.2032 0.3048)
							(mid 0.275042 0.275042)
							(end 0.3048 0.2032)
						)
					)
					(width 0)
					(fill yes)
				)
			)
		)
		(pad "2" smd custom
			(at 0 0.4445 90)
			(size 0.1524 0.1524)
			(layers "F.Cu" "F.Mask" "F.Paste")
			(net "GND")
			(options
				(clearance outline)
				(anchor circle)
			)
			(primitives
				(gr_poly
					(pts
						(arc
							(start 0.3048 -0.2032)
							(mid 0.275042 -0.275042)
							(end 0.2032 -0.3048)
						)
						(arc
							(start -0.2032 -0.3048)
							(mid -0.275042 -0.275042)
							(end -0.3048 -0.2032)
						)
						(arc
							(start -0.3048 0.2032)
							(mid -0.275042 0.275042)
							(end -0.2032 0.3048)
						)
						(arc
							(start 0.2032 0.3048)
							(mid 0.275042 0.275042)
							(end 0.3048 0.2032)
						)
					)
					(width 0)
					(fill yes)
				)
			)
		)
	)
	(footprint ""
		(layer "F.Cu")
		(at 70.104 -10.795 90)
		(property "Reference" "R245"
			(at 0 0 90)
			(layer "F.SilkS")
			(hide yes)
			(effects
				(font
					(size 1.27 1.27)
				)
			)
		)
		(property "Value" "0R2J-2-GP"
			(at 0.064008 -3.993896 90)
			(unlocked yes)
			(layer "F.Fab")
			(hide yes)
			(effects
				(font
					(size 1.016 1.016)
					(thickness 0.1524)
				)
			)
		)
		(property "Device Type" "R402H16"
			(at 0.064008 -5.517896 90)
			(unlocked yes)
			(layer "F.Fab")
			(hide yes)
			(effects
				(font
					(size 1.016 1.016)
					(thickness 0.1524)
				)
			)
		)
		(duplicate_pad_numbers_are_jumpers no)
		(fp_line
			(start 0.508 -0.9398)
			(end -0.508 -0.9398)
			(stroke
				(width 0.1524)
				(type default)
			)
			(layer "F.SilkS")
		)
		(fp_line
			(start -0.508 -0.9398)
			(end -0.508 0.9398)
			(stroke
				(width 0.1524)
				(type default)
			)
			(layer "F.SilkS")
		)
		(fp_rect
			(start -0.508 0.9398)
			(end 0.508 -0.9398)
			(stroke
				(width 0)
				(type default)
			)
			(fill no)
			(layer "F.CrtYd")
		)
		(fp_rect
			(start -0.508 0.9398)
			(end 0.508 -0.9398)
			(stroke
				(width 0)
				(type default)
			)
			(fill no)
			(layer "F.Fab")
		)
		(pad "1" smd custom
			(at 0 -0.4445 90)
			(size 0.1397 0.1397)
			(layers "F.Cu" "F.Mask" "F.Paste")
			(net "GND")
			(options
				(clearance outline)
				(anchor circle)
			)
			(primitives
				(gr_poly
					(pts
						(arc
							(start -0.1778 -0.2794)
							(mid -0.249642 -0.249642)
							(end -0.2794 -0.1778)
						)
						(arc
							(start -0.2794 0.1778)
							(mid -0.249642 0.249642)
							(end -0.1778 0.2794)
						)
						(arc
							(start 0.1778 0.2794)
							(mid 0.249642 0.249642)
							(end 0.2794 0.1778)
						)
						(arc
							(start 0.2794 -0.1778)
							(mid 0.249642 -0.249642)
							(end 0.1778 -0.2794)
						)
					)
					(width 0)
					(fill yes)
				)
			)
		)
		(pad "2" smd custom
			(at 0 0.4445 90)
			(size 0.1397 0.1397)
			(layers "F.Cu" "F.Mask" "F.Paste")
			(net "SCC_TYPE_3")
			(options
				(clearance outline)
				(anchor circle)
			)
			(primitives
				(gr_poly
					(pts
						(arc
							(start -0.1778 -0.2794)
							(mid -0.249642 -0.249642)
							(end -0.2794 -0.1778)
						)
						(arc
							(start -0.2794 0.1778)
							(mid -0.249642 0.249642)
							(end -0.1778 0.2794)
						)
						(arc
							(start 0.1778 0.2794)
							(mid 0.249642 0.249642)
							(end 0.2794 0.1778)
						)
						(arc
							(start 0.2794 -0.1778)
							(mid 0.249642 -0.249642)
							(end 0.1778 -0.2794)
						)
					)
					(width 0)
					(fill yes)
				)
			)
		)
	)
	(footprint ""
		(layer "F.Cu")
		(at 152.980898 -81.903824 -90)
		(property "Reference" "R326"
			(at 0 0 270)
			(layer "F.SilkS")
			(hide yes)
			(effects
				(font
					(size 1.27 1.27)
				)
			)
		)
		(property "Value" "0R2J-2-GP"
			(at 0.064008 -3.993896 270)
			(unlocked yes)
			(layer "F.Fab")
			(hide yes)
			(effects
				(font
					(size 1.016 1.016)
					(thickness 0.1524)
				)
			)
		)
		(property "Device Type" "R402H16"
			(at 0.064008 -5.517896 270)
			(unlocked yes)
			(layer "F.Fab")
			(hide yes)
			(effects
				(font
					(size 1.016 1.016)
					(thickness 0.1524)
				)
			)
		)
		(duplicate_pad_numbers_are_jumpers no)
		(fp_line
			(start -0.508 -0.9398)
			(end -0.508 0.9398)
			(stroke
				(width 0.1524)
				(type default)
			)
			(layer "F.SilkS")
		)
		(fp_line
			(start 0.508 -0.9398)
			(end -0.508 -0.9398)
			(stroke
				(width 0.1524)
				(type default)
			)
			(layer "F.SilkS")
		)
		(fp_rect
			(start -0.508 0.9398)
			(end 0.508 -0.9398)
			(stroke
				(width 0)
				(type default)
			)
			(fill no)
			(layer "F.CrtYd")
		)
		(fp_rect
			(start -0.508 0.9398)
			(end 0.508 -0.9398)
			(stroke
				(width 0)
				(type default)
			)
			(fill no)
			(layer "F.Fab")
		)
		(pad "1" smd custom
			(at 0 -0.4445 270)
			(size 0.1397 0.1397)
			(layers "F.Cu" "F.Mask" "F.Paste")
			(net "VOL_SEN1_SDA")
			(options
				(clearance outline)
				(anchor circle)
			)
			(primitives
				(gr_poly
					(pts
						(arc
							(start -0.1778 -0.2794)
							(mid -0.249642 -0.249642)
							(end -0.2794 -0.1778)
						)
						(arc
							(start -0.2794 0.1778)
							(mid -0.249642 0.249642)
							(end -0.1778 0.2794)
						)
						(arc
							(start 0.1778 0.2794)
							(mid 0.249642 0.249642)
							(end 0.2794 0.1778)
						)
						(arc
							(start 0.2794 -0.1778)
							(mid 0.249642 -0.249642)
							(end 0.1778 -0.2794)
						)
					)
					(width 0)
					(fill yes)
				)
			)
		)
		(pad "2" smd custom
			(at 0 0.4445 270)
			(size 0.1397 0.1397)
			(layers "F.Cu" "F.Mask" "F.Paste")
			(net "I2C_SCC_SDA2")
			(options
				(clearance outline)
				(anchor circle)
			)
			(primitives
				(gr_poly
					(pts
						(arc
							(start -0.1778 -0.2794)
							(mid -0.249642 -0.249642)
							(end -0.2794 -0.1778)
						)
						(arc
							(start -0.2794 0.1778)
							(mid -0.249642 0.249642)
							(end -0.1778 0.2794)
						)
						(arc
							(start 0.1778 0.2794)
							(mid 0.249642 0.249642)
							(end 0.2794 0.1778)
						)
						(arc
							(start 0.2794 -0.1778)
							(mid 0.249642 -0.249642)
							(end 0.1778 -0.2794)
						)
					)
					(width 0)
					(fill yes)
				)
			)
		)
	)
	(footprint ""
		(layer "F.Cu")
		(at 164.075872 -58.114438)
		(property "Reference" "R260"
			(at 0 0 0)
			(layer "F.SilkS")
			(hide yes)
			(effects
				(font
					(size 1.27 1.27)
				)
			)
		)
		(property "Value" "4K7R2F-GP"
			(at 0.064008 -3.993896 0)
			(unlocked yes)
			(layer "F.Fab")
			(hide yes)
			(effects
				(font
					(size 1.016 1.016)
					(thickness 0.1524)
				)
			)
		)
		(property "Device Type" "R402H16"
			(at 0.064008 -5.517896 0)
			(unlocked yes)
			(layer "F.Fab")
			(hide yes)
			(effects
				(font
					(size 1.016 1.016)
					(thickness 0.1524)
				)
			)
		)
		(duplicate_pad_numbers_are_jumpers no)
		(fp_line
			(start -0.508 -0.9398)
			(end -0.508 0.9398)
			(stroke
				(width 0.1524)
				(type default)
			)
			(layer "F.SilkS")
		)
		(fp_line
			(start 0.508 -0.9398)
			(end -0.508 -0.9398)
			(stroke
				(width 0.1524)
				(type default)
			)
			(layer "F.SilkS")
		)
		(fp_rect
			(start -0.508 0.9398)
			(end 0.508 -0.9398)
			(stroke
				(width 0)
				(type default)
			)
			(fill no)
			(layer "F.CrtYd")
		)
		(fp_rect
			(start -0.508 0.9398)
			(end 0.508 -0.9398)
			(stroke
				(width 0)
				(type default)
			)
			(fill no)
			(layer "F.Fab")
		)
		(pad "1" smd custom
			(at 0 -0.4445)
			(size 0.1397 0.1397)
			(layers "F.Cu" "F.Mask" "F.Paste")
			(net "P1V8_C")
			(options
				(clearance outline)
				(anchor circle)
			)
			(primitives
				(gr_poly
					(pts
						(arc
							(start -0.1778 -0.2794)
							(mid -0.249642 -0.249642)
							(end -0.2794 -0.1778)
						)
						(arc
							(start -0.2794 0.1778)
							(mid -0.249642 0.249642)
							(end -0.1778 0.2794)
						)
						(arc
							(start 0.1778 0.2794)
							(mid 0.249642 0.249642)
							(end 0.2794 0.1778)
						)
						(arc
							(start 0.2794 -0.1778)
							(mid 0.249642 -0.249642)
							(end 0.1778 -0.2794)
						)
					)
					(width 0)
					(fill yes)
				)
			)
		)
		(pad "2" smd custom
			(at 0 0.4445)
			(size 0.1397 0.1397)
			(layers "F.Cu" "F.Mask" "F.Paste")
			(net "ICE1_TRST#")
			(options
				(clearance outline)
				(anchor circle)
			)
			(primitives
				(gr_poly
					(pts
						(arc
							(start -0.1778 -0.2794)
							(mid -0.249642 -0.249642)
							(end -0.2794 -0.1778)
						)
						(arc
							(start -0.2794 0.1778)
							(mid -0.249642 0.249642)
							(end -0.1778 0.2794)
						)
						(arc
							(start 0.1778 0.2794)
							(mid 0.249642 0.249642)
							(end 0.2794 0.1778)
						)
						(arc
							(start 0.2794 -0.1778)
							(mid 0.249642 -0.249642)
							(end 0.1778 -0.2794)
						)
					)
					(width 0)
					(fill yes)
				)
			)
		)
	)
	(footprint ""
		(layer "F.Cu")
		(at 193.0654 -33.2486 -90)
		(property "Reference" "TP99"
			(at 0 0 270)
			(layer "F.SilkS")
			(hide yes)
			(effects
				(font
					(size 1.27 1.27)
				)
			)
		)
		(property "Value" "TPAD28-2-GP"
			(at -0.0127 -1.6637 270)
			(unlocked yes)
			(layer "F.Fab")
			(hide yes)
			(effects
				(font
					(size 1.016 1.016)
					(thickness 0.1524)
				)
			)
		)
		(property "Device Type" "TPAD28"
			(at -0.0127 -3.1877 270)
			(unlocked yes)
			(layer "F.Fab")
			(hide yes)
			(effects
				(font
					(size 1.016 1.016)
					(thickness 0.1524)
				)
			)
		)
		(duplicate_pad_numbers_are_jumpers no)
		(fp_poly
			(pts
				(arc
					(start 0 -0.3556)
					(mid 0 0.3556)
					(end 0 -0.3556)
				)
			)
			(stroke
				(width 0)
				(type default)
			)
			(fill no)
			(layer "F.CrtYd")
		)
		(fp_poly
			(pts
				(arc
					(start 0 -0.6096)
					(mid 0 0.6096)
					(end 0 -0.6096)
				)
			)
			(stroke
				(width 0)
				(type default)
			)
			(fill no)
			(layer "F.Fab")
		)
		(pad "1" smd circle
			(at 0 0 270)
			(size 0.7112 0.7112)
			(layers "F.Cu" "F.Mask" "F.Paste")
			(net "IOC_GPIO_37")
		)
	)
	(footprint ""
		(layer "F.Cu")
		(at 125.2728 -89.916)
		(property "Reference" "R113"
			(at 0 0 0)
			(layer "F.SilkS")
			(hide yes)
			(effects
				(font
					(size 1.27 1.27)
				)
			)
		)
		(property "Value" "4K75R2F-1-GP"
			(at 0.064008 -3.993896 0)
			(unlocked yes)
			(layer "F.Fab")
			(hide yes)
			(effects
				(font
					(size 1.016 1.016)
					(thickness 0.1524)
				)
			)
		)
		(property "Device Type" "R402H16"
			(at 0.064008 -5.517896 0)
			(unlocked yes)
			(layer "F.Fab")
			(hide yes)
			(effects
				(font
					(size 1.016 1.016)
					(thickness 0.1524)
				)
			)
		)
		(duplicate_pad_numbers_are_jumpers no)
		(fp_line
			(start -0.508 -0.9398)
			(end -0.508 0.9398)
			(stroke
				(width 0.1524)
				(type default)
			)
			(layer "F.SilkS")
		)
		(fp_line
			(start 0.508 -0.9398)
			(end -0.508 -0.9398)
			(stroke
				(width 0.1524)
				(type default)
			)
			(layer "F.SilkS")
		)
		(fp_rect
			(start -0.508 0.9398)
			(end 0.508 -0.9398)
			(stroke
				(width 0)
				(type default)
			)
			(fill no)
			(layer "F.CrtYd")
		)
		(fp_rect
			(start -0.508 0.9398)
			(end 0.508 -0.9398)
			(stroke
				(width 0)
				(type default)
			)
			(fill no)
			(layer "F.Fab")
		)
		(pad "1" smd custom
			(at 0 -0.4445)
			(size 0.1397 0.1397)
			(layers "F.Cu" "F.Mask" "F.Paste")
			(net "P1V8_E")
			(options
				(clearance outline)
				(anchor circle)
			)
			(primitives
				(gr_poly
					(pts
						(arc
							(start -0.1778 -0.2794)
							(mid -0.249642 -0.249642)
							(end -0.2794 -0.1778)
						)
						(arc
							(start -0.2794 0.1778)
							(mid -0.249642 0.249642)
							(end -0.1778 0.2794)
						)
						(arc
							(start 0.1778 0.2794)
							(mid 0.249642 0.249642)
							(end 0.2794 0.1778)
						)
						(arc
							(start 0.2794 -0.1778)
							(mid 0.249642 -0.249642)
							(end 0.1778 -0.2794)
						)
					)
					(width 0)
					(fill yes)
				)
			)
		)
		(pad "2" smd custom
			(at 0 0.4445)
			(size 0.1397 0.1397)
			(layers "F.Cu" "F.Mask" "F.Paste")
			(net "SDB_RX")
			(options
				(clearance outline)
				(anchor circle)
			)
			(primitives
				(gr_poly
					(pts
						(arc
							(start -0.1778 -0.2794)
							(mid -0.249642 -0.249642)
							(end -0.2794 -0.1778)
						)
						(arc
							(start -0.2794 0.1778)
							(mid -0.249642 0.249642)
							(end -0.1778 0.2794)
						)
						(arc
							(start 0.1778 0.2794)
							(mid 0.249642 0.249642)
							(end 0.2794 0.1778)
						)
						(arc
							(start 0.2794 -0.1778)
							(mid 0.249642 -0.249642)
							(end 0.1778 -0.2794)
						)
					)
					(width 0)
					(fill yes)
				)
			)
		)
	)
)
